
INPUT-UNITS     INCHES

WHEEL     1

RECTANGLE         12        21   0.00000  D10
RECTANGLE         21        12   0.00000  D11
RECTANGLE         16        25   0.00000  D12
RECTANGLE         25        16   0.00000  D13
RECTANGLE         11        20   0.00000  D14
RECTANGLE         20        11   0.00000  D15
RECTANGLE         15        24   0.00000  D16
RECTANGLE         24        15   0.00000  D17
CIRCLE            71            D18
FLASH     TR57X71X15-45        0.00000  D19
CIRCLE            41            D20
CIRCLE            61            D21
RECTANGLE         12        20   0.00000  D22
RECTANGLE         20        12   0.00000  D23
RECTANGLE         16        24   0.00000  D24
RECTANGLE         24        16   0.00000  D25
RECTANGLE         16       4.1   0.00000  D26
RECTANGLE        4.1        16   0.00000  D27
RECTANGLE         16       8.1   0.00000  D28
RECTANGLE        8.1        16   0.00000  D29
CIRCLE           142            D30
FLASH     TR138X152X40-45      0.00000  D31
CIRCLE           122            D32
RECTANGLE         24        42   0.00000  D33
RECTANGLE         42        24   0.00000  D34
RECTANGLE         28        46   0.00000  D35
RECTANGLE         46        28   0.00000  D36
RECTANGLE         12        36   0.00000  D37
RECTANGLE         36        12   0.00000  D38
RECTANGLE         16        40   0.00000  D39
RECTANGLE         40        16   0.00000  D40
RECTANGLE         78       107   0.00000  D41
RECTANGLE        107        78   0.00000  D42
RECTANGLE         82       111   0.00000  D43
RECTANGLE        111        82   0.00000  D44
RECTANGLE         11        24   0.00000  D45
RECTANGLE         24        11   0.00000  D46
RECTANGLE         15        28   0.00000  D47
RECTANGLE         28        15   0.00000  D48
CIRCLE           241            D49
FLASH     TR237X251X40-45      0.00000  D50
CIRCLE           394            D51
CIRCLE           398            D52
CIRCLE            30            D53
FLASH     TR_C5-ALL            0.00000  D54
CIRCLE            20            D55
CIRCLE            28            D56
CIRCLE            32            D57
CIRCLE          19.3            D58
CIRCLE            26            D59
CIRCLE            24            D60
CIRCLE            18            D61
CIRCLE            16            D62
CIRCLE           186            D63
FLASH     TR182X196X40-45      0.00000  D64
CIRCLE           315            D65
CIRCLE           319            D66
RECTANGLE         16        44   0.00000  D67
RECTANGLE         44        16   0.00000  D68
RECTANGLE         20        48   0.00000  D69
RECTANGLE         48        20   0.00000  D70
RECTANGLE         22        40   0.00000  D71
RECTANGLE         40        22   0.00000  D72
RECTANGLE         24        95   0.00000  D73
RECTANGLE         95        24   0.00000  D74
RECTANGLE         28        99   0.00000  D75
RECTANGLE         99        28   0.00000  D76
RECTANGLE         20        91   0.00000  D77
RECTANGLE         91        20   0.00000  D78
SQUARE           168   0.00000            D79
SQUARE           172   0.00000            D80
CIRCLE            60            D81
FLASH     TR46X60X15-45        0.00000  D82
CIRCLE            50            D83
RECTANGLE         35       231   0.00000  D84
RECTANGLE        231        35   0.00000  D85
RECTANGLE        126       270   0.00000  D86
RECTANGLE        270       126   0.00000  D87
RECTANGLE        130       274   0.00000  D88
RECTANGLE        274       130   0.00000  D89
RECTANGLE         32        50   0.00000  D90
RECTANGLE         50        32   0.00000  D91
RECTANGLE        128       135   0.00000  D92
RECTANGLE        135       128   0.00000  D93
RECTANGLE        132       139   0.00000  D94
RECTANGLE        139       132   0.00000  D95
CIRCLE            52            D96
FLASH     TR48X62X15-45        0.00000  D97
CIRCLE            48            D98
CIRCLE            82            D99
FLASH     TR68X82X15-45        0.00000  D100
CIRCLE            72            D101
RECTANGLE         18        20   0.00000  D102
RECTANGLE         20        18   0.00000  D103
RECTANGLE         22        24   0.00000  D104
RECTANGLE         24        22   0.00000  D105
CIRCLE            40            D106
CIRCLE           120            D107
CIRCLE           155            D108
FLASH     TR141X155X40-45      0.00000  D109
CIRCLE           125            D110
CIRCLE           145            D111
CIRCLE           256            D112
CIRCLE           260            D113
RECTANGLE        116       146   0.00000  D114
RECTANGLE        146       116   0.00000  D115
RECTANGLE        120       150   0.00000  D116
RECTANGLE        150       120   0.00000  D117
CIRCLE           208            D118
FLASH     TR194X208X40-45      0.00000  D119
CIRCLE           178            D120
CIRCLE           198            D121
CIRCLE           164            D122
FLASH     TR150X164X40-45      0.00000  D123
CIRCLE           134            D124
CIRCLE           154            D125
RECTANGLE         46        69   0.00000  D126
RECTANGLE         69        46   0.00000  D127
RECTANGLE         50        73   0.00000  D128
RECTANGLE         73        50   0.00000  D129
FLASH     TR_C6-ALL            0.00000  D130
CIRCLE           146            D131
FLASH     TR142X156X40-45      0.00000  D132
RECTANGLE         10        50   0.00000  D133
RECTANGLE         50        10   0.00000  D134
RECTANGLE         14        54   0.00000  D135
RECTANGLE         54        14   0.00000  D136
RECTANGLE         10        32   0.00000  D137
RECTANGLE         32        10   0.00000  D138
RECTANGLE         14        36   0.00000  D139
RECTANGLE         36        14   0.00000  D140
RECTANGLE         59        79   0.00000  D141
RECTANGLE         79        59   0.00000  D142
RECTANGLE         63        83   0.00000  D143
RECTANGLE         83        63   0.00000  D144
RECTANGLE         40        15   0.00000  D145
RECTANGLE         15        40   0.00000  D146
RECTANGLE         44        19   0.00000  D147
RECTANGLE         19        44   0.00000  D148
RECTANGLE         14        58   0.00000  D149
RECTANGLE         58        14   0.00000  D150
RECTANGLE         38        56   0.00000  D151
RECTANGLE         56        38   0.00000  D152
RECTANGLE         42        60   0.00000  D153
RECTANGLE         60        42   0.00000  D154
RECTANGLE         22        56   0.00000  D155
RECTANGLE         56        22   0.00000  D156
RECTANGLE         26        60   0.00000  D157
RECTANGLE         60        26   0.00000  D158
RECTANGLE         24        52   0.00000  D159
RECTANGLE         52        24   0.00000  D160
RECTANGLE         28        56   0.00000  D161
RECTANGLE         56        28   0.00000  D162
RECTANGLE         16        54   0.00000  D163
RECTANGLE         54        16   0.00000  D164
RECTANGLE         20        58   0.00000  D165
RECTANGLE         58        20   0.00000  D166
RECTANGLE         24        54   0.00000  D167
RECTANGLE         54        24   0.00000  D168
RECTANGLE         28        58   0.00000  D169
RECTANGLE         58        28   0.00000  D170
RECTANGLE         32        75   0.00000  D171
RECTANGLE         75        32   0.00000  D172
RECTANGLE         36        79   0.00000  D173
RECTANGLE         79        36   0.00000  D174
RECTANGLE         28        71   0.00000  D175
RECTANGLE         71        28   0.00000  D176
RECTANGLE         40        48   0.00000  D177
RECTANGLE         48        40   0.00000  D178
RECTANGLE         44        52   0.00000  D179
RECTANGLE         52        44   0.00000  D180
RECTANGLE         24        28   0.00000  D181
RECTANGLE         28        24   0.00000  D182
RECTANGLE         28        32   0.00000  D183
RECTANGLE         32        28   0.00000  D184
RECTANGLE         32        34   0.00000  D185
RECTANGLE         34        32   0.00000  D186
RECTANGLE         36        38   0.00000  D187
RECTANGLE         38        36   0.00000  D188
RECTANGLE         14        48   0.00000  D189
RECTANGLE         48        14   0.00000  D190
RECTANGLE         18        52   0.00000  D191
RECTANGLE         52        18   0.00000  D192
CIRCLE            64            D193
FLASH     TR60X74X15-45        0.00000  D194
CIRCLE            68            D195
CIRCLE            74            D196
CIRCLE            44            D197
LINE              74            D198
OBLONG            74       127   0.00000  D199
OBLONG           127        74   0.00000  D200
FLASH     B60-113X74-127X15    0.00000  D201
LINE              62            D202
OBLONG            62       137   0.00000  D203
OBLONG           137        62   0.00000  D204
LINE              66            D205
OBLONG            66       141   0.00000  D206
OBLONG           141        66   0.00000  D207
LINE              64            D208
OBLONG            64       137   0.00000  D209
OBLONG           137        64   0.00000  D210
LINE              68            D211
OBLONG            68       141   0.00000  D212
OBLONG           141        68   0.00000  D213
RECTANGLE        186       189   0.00000  D214
RECTANGLE        189       186   0.00000  D215
RECTANGLE        190       193   0.00000  D216
RECTANGLE        193       190   0.00000  D217
RECTANGLE         50        56   0.00000  D218
RECTANGLE         56        50   0.00000  D219
RECTANGLE         54        60   0.00000  D220
RECTANGLE         60        54   0.00000  D221
RECTANGLE         40       109   0.00000  D222
RECTANGLE        109        40   0.00000  D223
RECTANGLE         44       113   0.00000  D224
RECTANGLE        113        44   0.00000  D225
RECTANGLE         46        63   0.00000  D226
RECTANGLE         63        46   0.00000  D227
RECTANGLE         50        67   0.00000  D228
RECTANGLE         67        50   0.00000  D229
RECTANGLE          9        15   0.00000  D230
RECTANGLE         15         9   0.00000  D231
RECTANGLE         13        19   0.00000  D232
RECTANGLE         19        13   0.00000  D233
SQUARE           134   0.00000            D234
SQUARE           138   0.00000            D235
RECTANGLE         10        15   0.00000  D236
RECTANGLE         15        10   0.00000  D237
RECTANGLE         14        19   0.00000  D238
RECTANGLE         19        14   0.00000  D239
RECTANGLE         10        14   0.00000  D240
RECTANGLE         14        10   0.00000  D241
RECTANGLE         14        18   0.00000  D242
RECTANGLE         18        14   0.00000  D243
RECTANGLE         48        59   0.00000  D244
RECTANGLE         59        48   0.00000  D245
RECTANGLE         52        63   0.00000  D246
RECTANGLE         63        52   0.00000  D247
RECTANGLE         36        40   0.00000  D248
RECTANGLE         40        36   0.00000  D249
RECTANGLE         40        44   0.00000  D250
RECTANGLE         44        40   0.00000  D251
RECTANGLE         48        56   0.00000  D252
RECTANGLE         56        48   0.00000  D253
RECTANGLE         52        60   0.00000  D254
RECTANGLE         60        52   0.00000  D255
RECTANGLE         24        44   0.00000  D256
RECTANGLE         44        24   0.00000  D257
RECTANGLE         28        48   0.00000  D258
RECTANGLE         48        28   0.00000  D259
RECTANGLE         14        52   0.00000  D260
RECTANGLE         52        14   0.00000  D261
RECTANGLE         18        56   0.00000  D262
RECTANGLE         56        18   0.00000  D263
RECTANGLE         14        59   0.00000  D264
RECTANGLE         59        14   0.00000  D265
RECTANGLE         18        63   0.00000  D266
RECTANGLE         63        18   0.00000  D267
RECTANGLE         12        63   0.00000  D268
RECTANGLE         63        12   0.00000  D269
RECTANGLE         16        67   0.00000  D270
RECTANGLE         67        16   0.00000  D271
RECTANGLE         10        61   0.00000  D272
RECTANGLE         61        10   0.00000  D273
RECTANGLE         24        46   0.00000  D274
RECTANGLE         46        24   0.00000  D275
RECTANGLE         28        50   0.00000  D276
RECTANGLE         50        28   0.00000  D277
RECTANGLE         17        46   0.00000  D278
RECTANGLE         46        17   0.00000  D279
RECTANGLE         21        50   0.00000  D280
RECTANGLE         50        21   0.00000  D281
SQUARE           124   0.00000            D282
SQUARE           128   0.00000            D283
SQUARE           166   0.00000            D284
SQUARE           170   0.00000            D285
CIRCLE             9            D286
CIRCLE            13            D287
RECTANGLE          7        22   0.00000  D288
RECTANGLE         22         7   0.00000  D289
RECTANGLE         11        26   0.00000  D290
RECTANGLE         26        11   0.00000  D291
SQUARE           140   0.00000            D292
SQUARE           144   0.00000            D293
RECTANGLE         10        29   0.00000  D294
RECTANGLE         29        10   0.00000  D295
RECTANGLE         14        33   0.00000  D296
RECTANGLE         33        14   0.00000  D297
RECTANGLE         24        32   0.00000  D298
RECTANGLE         32        24   0.00000  D299
RECTANGLE         28        36   0.00000  D300
RECTANGLE         36        28   0.00000  D301
RECTANGLE          6        28   0.00000  D302
RECTANGLE         28         6   0.00000  D303
RECTANGLE          7        20   0.00000  D304
RECTANGLE         20         7   0.00000  D305
RECTANGLE         28        40   0.00000  D306
RECTANGLE         40        28   0.00000  D307
RECTANGLE         32        44   0.00000  D308
RECTANGLE         44        32   0.00000  D309
RECTANGLE         24        36   0.00000  D310
RECTANGLE         36        24   0.00000  D311
RECTANGLE         20        24   0.00000  D312
RECTANGLE         24        20   0.00000  D313
RECTANGLE         14        44   0.00000  D314
RECTANGLE         44        14   0.00000  D315
RECTANGLE         18        48   0.00000  D316
RECTANGLE         48        18   0.00000  D317
RECTANGLE         85        89   0.00000  D318
RECTANGLE         89        85   0.00000  D319
RECTANGLE         89        93   0.00000  D320
RECTANGLE         93        89   0.00000  D321
LINE              50            D322
OBLONG            50        93   0.00000  D323
OBLONG            93        50   0.00000  D324
FLASH     B36-79X50-93X15      0.00000  D325
LINE              44            D326
OBLONG            44        87   0.00000  D327
OBLONG            87        44   0.00000  D328
LINE              48            D329
OBLONG            48        91   0.00000  D330
OBLONG            91        48   0.00000  D331
OBLONG            50        78   0.00000  D332
OBLONG            78        50   0.00000  D333
FLASH     B36-64X50-78X15      0.00000  D334
OBLONG            44        71   0.00000  D335
OBLONG            71        44   0.00000  D336
OBLONG            48        75   0.00000  D337
OBLONG            75        48   0.00000  D338
RECTANGLE         17        59   0.00000  D339
RECTANGLE         59        17   0.00000  D340
RECTANGLE         21        63   0.00000  D341
RECTANGLE         63        21   0.00000  D342
RECTANGLE         14        63   0.00000  D343
RECTANGLE         63        14   0.00000  D344
RECTANGLE         18        67   0.00000  D345
RECTANGLE         67        18   0.00000  D346
RECTANGLE         12        61   0.00000  D347
RECTANGLE         61        12   0.00000  D348
RECTANGLE         11        54   0.00000  D349
RECTANGLE         54        11   0.00000  D350
RECTANGLE         15        58   0.00000  D351
RECTANGLE         58        15   0.00000  D352
RECTANGLE         25        48   0.00000  D353
RECTANGLE         48        25   0.00000  D354
RECTANGLE         29        52   0.00000  D355
RECTANGLE         52        29   0.00000  D356
RECTANGLE         11        28   0.00000  D357
RECTANGLE         28        11   0.00000  D358
RECTANGLE         15        32   0.00000  D359
RECTANGLE         32        15   0.00000  D360
RECTANGLE         22        68   0.00000  D361
RECTANGLE         68        22   0.00000  D362
RECTANGLE         26        72   0.00000  D363
RECTANGLE         72        26   0.00000  D364
RECTANGLE        115       138   0.00000  D365
RECTANGLE        138       115   0.00000  D366
RECTANGLE        119       142   0.00000  D367
RECTANGLE        142       119   0.00000  D368
CIRCLE          32.2            D369
FLASH     TR_C10-ALL           0.00000  D370
CIRCLE          28.2            D371
SQUARE          28.2   0.00000            D372
SQUARE          32.2   0.00000            D373
SQUARE            67   0.00000            D374
SQUARE            71   0.00000            D375
RECTANGLE         10        22   0.00000  D376
RECTANGLE         22        10   0.00000  D377
RECTANGLE         14        26   0.00000  D378
RECTANGLE         26        14   0.00000  D379
RECTANGLE         63       138   0.00000  D380
RECTANGLE        138        63   0.00000  D381
RECTANGLE         67       142   0.00000  D382
RECTANGLE        142        67   0.00000  D383
RECTANGLE         11        18   0.00000  D384
RECTANGLE         18        11   0.00000  D385
RECTANGLE         15        22   0.00000  D386
RECTANGLE         22        15   0.00000  D387
RECTANGLE         46       386   0.00000  D388
RECTANGLE        386        46   0.00000  D389
RECTANGLE         46        71   0.00000  D390
RECTANGLE         71        46   0.00000  D391
RECTANGLE         10        28   0.00000  D392
RECTANGLE         28        10   0.00000  D393
RECTANGLE         14        32   0.00000  D394
RECTANGLE         32        14   0.00000  D395
RECTANGLE         69       105   0.00000  D396
RECTANGLE        105        69   0.00000  D397
RECTANGLE         73       109   0.00000  D398
RECTANGLE        109        73   0.00000  D399
RECTANGLE         67        99   0.00000  D400
RECTANGLE         99        67   0.00000  D401
RECTANGLE         71       103   0.00000  D402
RECTANGLE        103        71   0.00000  D403
RECTANGLE         28        52   0.00000  D404
RECTANGLE         52        28   0.00000  D405
RECTANGLE         32        56   0.00000  D406
RECTANGLE         56        32   0.00000  D407
RECTANGLE         11        32   0.00000  D408
RECTANGLE         32        11   0.00000  D409
RECTANGLE         15        36   0.00000  D410
RECTANGLE         36        15   0.00000  D411
RECTANGLE         73       138   0.00000  D412
RECTANGLE        138        73   0.00000  D413
RECTANGLE         77       142   0.00000  D414
RECTANGLE        142        77   0.00000  D415
CIRCLE            65            D416
SQUARE            61   0.00000            D417
SQUARE            65   0.00000            D418
RECTANGLE         14        61   0.00000  D419
RECTANGLE         61        14   0.00000  D420
RECTANGLE         18        65   0.00000  D421
RECTANGLE         65        18   0.00000  D422
RECTANGLE         95       130   0.00000  D423
RECTANGLE        130        95   0.00000  D424
RECTANGLE         99       134   0.00000  D425
RECTANGLE        134        99   0.00000  D426
RECTANGLE         10        20   0.00000  D427
RECTANGLE         20        10   0.00000  D428
RECTANGLE         14        24   0.00000  D429
RECTANGLE         24        14   0.00000  D430
RECTANGLE         32        36   0.00000  D431
RECTANGLE         36        32   0.00000  D432
RECTANGLE         11        36   0.00000  D433
RECTANGLE         36        11   0.00000  D434
RECTANGLE         12        79   0.00000  D435
RECTANGLE         79        12   0.00000  D436
RECTANGLE         16        83   0.00000  D437
RECTANGLE         83        16   0.00000  D438
RECTANGLE         12        32   0.00000  D439
RECTANGLE         32        12   0.00000  D440
RECTANGLE         16        36   0.00000  D441
RECTANGLE         36        16   0.00000  D442
RECTANGLE          7        32   0.00000  D443
RECTANGLE         32         7   0.00000  D444
RECTANGLE        130     169.2   0.00000  D445
RECTANGLE      169.2       130   0.00000  D446
RECTANGLE        134     173.2   0.00000  D447
RECTANGLE      173.2       134   0.00000  D448
RECTANGLE         42        99   0.00000  D449
RECTANGLE         99        42   0.00000  D450
RECTANGLE         46       103   0.00000  D451
RECTANGLE        103        46   0.00000  D452
CIRCLE            42            D453
FLASH     TR_C20-ALL           0.00000  D454
CIRCLE            34            D455
CIRCLE            99            D456
FLASH     TR95X109X25-45       0.00000  D457
RECTANGLE        166       197   0.00000  D458
RECTANGLE        197       166   0.00000  D459
CIRCLE           158            D460
RECTANGLE        170       201   0.00000  D461
RECTANGLE        201       170   0.00000  D462
CIRCLE           162            D463
CIRCLE            87            D464
FLASH     TR83X97X25-45        0.00000  D465
CIRCLE            85            D466
CIRCLE          78.5            D467
CIRCLE          43.5            D468
CIRCLE          31.5            D469
CIRCLE          39.5            D470
RECTANGLE         44        54   0.00000  D471
RECTANGLE         54        44   0.00000  D472
RECTANGLE         48        58   0.00000  D473
RECTANGLE         58        48   0.00000  D474
RECTANGLE         12        18   0.00000  D475
RECTANGLE         18        12   0.00000  D476
RECTANGLE         16        22   0.00000  D477
RECTANGLE         22        16   0.00000  D478
RECTANGLE         24       170   0.00000  D479
RECTANGLE        170        24   0.00000  D480
RECTANGLE         28       174   0.00000  D481
RECTANGLE        174        28   0.00000  D482
RECTANGLE         81        91   0.00000  D483
RECTANGLE         91        81   0.00000  D484
RECTANGLE         85        95   0.00000  D485
RECTANGLE         95        85   0.00000  D486
RECTANGLE         69        77   0.00000  D487
RECTANGLE         77        69   0.00000  D488
RECTANGLE         73        81   0.00000  D489
RECTANGLE         81        73   0.00000  D490
RECTANGLE          9        24   0.00000  D491
RECTANGLE         24         9   0.00000  D492
RECTANGLE         13        28   0.00000  D493
RECTANGLE         28        13   0.00000  D494
RECTANGLE          7        24   0.00000  D495
RECTANGLE         24         7   0.00000  D496
SQUARE           148   0.00000            D497
RECTANGLE        122       132   0.00000  D498
RECTANGLE        132       122   0.00000  D499
RECTANGLE        126       136   0.00000  D500
RECTANGLE        136       126   0.00000  D501
RECTANGLE         50       135   0.00000  D502
RECTANGLE        135        50   0.00000  D503
RECTANGLE         54       139   0.00000  D504
RECTANGLE        139        54   0.00000  D505
RECTANGLE         95       111   0.00000  D506
RECTANGLE        111        95   0.00000  D507
RECTANGLE         99       115   0.00000  D508
RECTANGLE        115        99   0.00000  D509
RECTANGLE         63       119   0.00000  D510
RECTANGLE        119        63   0.00000  D511
RECTANGLE         67       123   0.00000  D512
RECTANGLE        123        67   0.00000  D513
RECTANGLE       84.8       130   0.00000  D514
RECTANGLE        130      84.8   0.00000  D515
RECTANGLE       88.8       134   0.00000  D516
RECTANGLE        134      88.8   0.00000  D517
RECTANGLE         40        56   0.00000  D518
RECTANGLE         56        40   0.00000  D519
RECTANGLE         44        60   0.00000  D520
RECTANGLE         60        44   0.00000  D521
RECTANGLE         20        28   0.00000  D522
RECTANGLE         28        20   0.00000  D523
RECTANGLE         24        24   0.00000  D524
RECTANGLE         28        28   0.00000  D525
RECTANGLE         20        20   0.00000  D526
RECTANGLE         22        53   0.00000  D527
RECTANGLE         53        22   0.00000  D528
RECTANGLE         26        57   0.00000  D529
RECTANGLE         57        26   0.00000  D530
RECTANGLE         20        40   0.00000  D531
RECTANGLE         40        20   0.00000  D532
RECTANGLE         14        34   0.00000  D533
RECTANGLE         34        14   0.00000  D534
RECTANGLE         20        60   0.00000  D535
RECTANGLE         60        20   0.00000  D536
RECTANGLE         24        64   0.00000  D537
RECTANGLE         64        24   0.00000  D538
RECTANGLE         17        24   0.00000  D539
RECTANGLE         24        17   0.00000  D540
RECTANGLE         21        28   0.00000  D541
RECTANGLE         28        21   0.00000  D542
CIRCLE            22            D543
RECTANGLE         15        50   0.00000  D544
RECTANGLE         50        15   0.00000  D545
RECTANGLE         19        54   0.00000  D546
RECTANGLE         54        19   0.00000  D547
RECTANGLE         15        53   0.00000  D548
RECTANGLE         53        15   0.00000  D549
RECTANGLE         19        57   0.00000  D550
RECTANGLE         57        19   0.00000  D551
CIRCLE         39.68            D552
FLASH     TR_C17-ALL           0.00000  D553
CIRCLE         35.68            D554
CIRCLE         59.99            D555
FLASH     TR_C37-ALL           0.00000  D556
CIRCLE         70.51            D557
CIRCLE         74.51            D558
SQUARE         70.51   0.00000            D559
SQUARE         74.51   0.00000            D560
RECTANGLE         12        15   0.00000  D561
RECTANGLE         15        12   0.00000  D562
RECTANGLE         16        19   0.00000  D563
RECTANGLE         19        16   0.00000  D564
RECTANGLE         40        50   0.00000  D565
RECTANGLE         50        40   0.00000  D566
LINE               6            D567
LINE               2            D568
LINE               1            D569
LINE               4            D570
LINE               8            D571
LINE              10            D572
LINE              25            D573
LINE             5.2            D574
LINE              18            D575
LINE               7            D576
LINE              40            D577
LINE             6.1            D578
LINE              20            D579
LINE             120            D580
LINE             3.5            D581
LINE            9.84            D582
LINE             5.3            D583
LINE             6.5            D584
LINE             4.5            D585
LINE              15            D586
LINE              14            D587
LINE              16            D588
LINE              12            D589
LINE               5            D590
LINE              11            D591
LINE               9            D592
LINE            3.25            D593
LINE              60            D594
LINE             4.6            D595
LINE             4.3            D596
LINE              17            D597
LINE            2.25            D598
LINE             5.5            D599
LINE             3.9            D600
LINE            2.65            D601
LINE            1.75            D602
LINE            2.75            D603

